# BASEBOARD_FAB2 (Tioga Pass) — schematic netlist excerpt (pin names and nets, part order shuffled) for the footprints in the layout excerpt that follows; sources: Cadence DE-HDL packaged netlist, KiCad conversion of Wiwynn_Tioga_Pass_MB.brd

U8D4  AT24C64  IC  pkg SOICLF  page 167
  A0  = GND
  A1  = GND
  A2  = PU_AT24C64_A2
  SDA  = SMB_SENSOR_STBY_LVC3_SDA_R2
  SCL  = SMB_SENSOR_STBY_LVC3_SCL_R2
  WP  = PD_FRU_WP

Y7C2  CRYSTAL  32.768KHZ IC  pkg SM  page 114 : A = XTAL_33K_RTC1 ; B = XTAL_33K_RTC2

(kicad_pcb
	(version 20260206)
	(generator "pcbnew")
	(generator_version "10.0")
	(general
		(thickness 1.6)
		(legacy_teardrops no)
	)
	(paper "A4")
	(title_block
		(title "Wiwynn_Tioga_Pass_MB.brd")
		(comment 1 "Tioga Pass / footprints 1987-1988 of 4770")
	)
	(layers
		(0 "F.Cu" signal "TOP")
		(4 "In1.Cu" signal "L2GND")
		(6 "In2.Cu" signal "L3")
		(8 "In3.Cu" signal "L4GND")
		(10 "In4.Cu" signal "L5")
		(12 "In5.Cu" signal "L6GND")
		(14 "In6.Cu" signal "L7VCC")
		(16 "In7.Cu" signal "L8VCC")
		(18 "In8.Cu" signal "L9GND")
		(20 "In9.Cu" signal "L10")
		(22 "In10.Cu" signal "L11GND")
		(24 "In11.Cu" signal "L12")
		(26 "In12.Cu" signal "L13GND")
		(2 "B.Cu" signal "BOTTOM")
		(9 "F.Adhes" user "F.Adhesive")
		(11 "B.Adhes" user "B.Adhesive")
		(13 "F.Paste" user "Package Geometry/Pastemask Top")
		(15 "B.Paste" user "Package Geometry/Pastemask Bottom")
		(5 "F.SilkS" user "Ref Des/Silkscreen Top")
		(7 "B.SilkS" user "Ref Des/Silkscreen Bottom")
		(1 "F.Mask" user "Board Geometry/Soldermask Top")
		(3 "B.Mask" user "Board Geometry/Soldermask Bottom")
		(17 "Dwgs.User" user "User.Drawings")
		(19 "Cmts.User" user "User.Comments")
		(21 "Eco1.User" user "User.Eco1")
		(23 "Eco2.User" user "User.Eco2")
		(25 "Edge.Cuts" user "Board Geometry/Outline")
		(27 "Margin" user)
		(31 "F.CrtYd" user "Package Geometry/Place Bound Top")
		(29 "B.CrtYd" user "Package Geometry/Place Bound Bottom")
		(35 "F.Fab" user "Ref Des/Assembly Top")
		(33 "B.Fab" user "Ref Des/Assembly Bottom")
	)
	(footprint ""
		(layer "F.Cu")
		(at 411.6832 -51.308 180)
		(property "Reference" "U8D4"
			(at 1.778 5.09143 0)
			(unlocked yes)
			(layer "F.SilkS")
			(effects
				(font
					(size 0.7874 0.5842)
					(thickness 0.1524)
				)
				(justify left)
			)
		)
		(property "Value" ""
			(at 0 0 180)
			(layer "F.Fab")
			(effects
				(font
					(size 1.27 1.27)
				)
			)
		)
		(duplicate_pad_numbers_are_jumpers no)
		(fp_line
			(start 4.191 4.4069)
			(end 1.2954 4.4069)
			(stroke
				(width 0.1524)
				(type default)
			)
			(layer "F.SilkS")
		)
		(fp_line
			(start 4.191 -0.5969)
			(end 4.191 4.4069)
			(stroke
				(width 0.1524)
				(type default)
			)
			(layer "F.SilkS")
		)
		(fp_line
			(start 3.3782 0.6731)
			(end 3.3782 -0.5842)
			(stroke
				(width 0.1524)
				(type default)
			)
			(layer "F.SilkS")
		)
		(fp_line
			(start 2.1082 0.6731)
			(end 3.3782 0.6731)
			(stroke
				(width 0.1524)
				(type default)
			)
			(layer "F.SilkS")
		)
		(fp_line
			(start 2.1082 -0.5842)
			(end 2.1082 0.6731)
			(stroke
				(width 0.1524)
				(type default)
			)
			(layer "F.SilkS")
		)
		(fp_line
			(start 1.2954 4.4069)
			(end 1.2954 -0.5969)
			(stroke
				(width 0.1524)
				(type default)
			)
			(layer "F.SilkS")
		)
		(fp_line
			(start 1.2954 -0.5969)
			(end 4.191 -0.5969)
			(stroke
				(width 0.1524)
				(type default)
			)
			(layer "F.SilkS")
		)
		(fp_circle
			(center -1.37414 -0.541528)
			(end -1.50114 -0.541528)
			(stroke
				(width 0.254)
				(type default)
			)
			(fill no)
			(layer "F.SilkS")
		)
		(fp_poly
			(pts
				(xy 0.7493 -0.5969) (xy 4.7371 -0.5969) (xy 4.7371 4.4069) (xy 0.7493 4.4069)
			)
			(stroke
				(width 0)
				(type default)
			)
			(fill no)
			(layer "F.CrtYd")
		)
		(fp_line
			(start 4.7371 4.4069)
			(end 0.7493 4.4069)
			(stroke
				(width 0.1)
				(type default)
			)
			(layer "F.Fab")
		)
		(fp_line
			(start 4.7371 -0.5969)
			(end 4.7371 4.4069)
			(stroke
				(width 0.1)
				(type default)
			)
			(layer "F.Fab")
		)
		(fp_line
			(start 3.3782 0.6731)
			(end 3.3782 -0.5842)
			(stroke
				(width 0.1)
				(type default)
			)
			(layer "F.Fab")
		)
		(fp_line
			(start 2.1082 0.6731)
			(end 3.3782 0.6731)
			(stroke
				(width 0.1)
				(type default)
			)
			(layer "F.Fab")
		)
		(fp_line
			(start 2.1082 -0.5842)
			(end 2.1082 0.6731)
			(stroke
				(width 0.1)
				(type default)
			)
			(layer "F.Fab")
		)
		(fp_line
			(start 0.7493 4.4069)
			(end 0.7493 -0.5969)
			(stroke
				(width 0.1)
				(type default)
			)
			(layer "F.Fab")
		)
		(fp_line
			(start 0.7493 -0.5969)
			(end 4.7371 -0.5969)
			(stroke
				(width 0.1)
				(type default)
			)
			(layer "F.Fab")
		)
		(fp_circle
			(center -1.382014 -0.7112)
			(end -1.509014 -0.7112)
			(stroke
				(width 0.254)
				(type default)
			)
			(fill no)
			(layer "F.Fab")
		)
		(pad "1" smd rect
			(at 0 0 180)
			(size 1.9304 0.635)
			(layers "F.Cu" "F.Mask" "F.Paste")
			(net "GND")
		)
		(pad "2" smd rect
			(at 0 1.27 180)
			(size 1.9304 0.635)
			(layers "F.Cu" "F.Mask" "F.Paste")
			(net "GND")
		)
		(pad "3" smd rect
			(at 0 2.54 180)
			(size 1.9304 0.635)
			(layers "F.Cu" "F.Mask" "F.Paste")
			(net "PU_AT24C64_A2")
		)
		(pad "4" smd rect
			(at 0 3.81 180)
			(size 1.9304 0.635)
			(layers "F.Cu" "F.Mask" "F.Paste")
			(net "GND")
		)
		(pad "5" smd rect
			(at 5.4864 3.81 180)
			(size 1.9304 0.635)
			(layers "F.Cu" "F.Mask" "F.Paste")
			(net "SMB_SENSOR_STBY_LVC3_SDA_R2")
		)
		(pad "6" smd rect
			(at 5.4864 2.54 180)
			(size 1.9304 0.635)
			(layers "F.Cu" "F.Mask" "F.Paste")
			(net "SMB_SENSOR_STBY_LVC3_SCL_R2")
		)
		(pad "7" smd rect
			(at 5.4864 1.27 180)
			(size 1.9304 0.635)
			(layers "F.Cu" "F.Mask" "F.Paste")
			(net "PD_FRU_WP")
		)
		(pad "8" smd rect
			(at 5.4864 0 180)
			(size 1.9304 0.635)
			(layers "F.Cu" "F.Mask" "F.Paste")
			(net "P3V3_STBY")
		)
	)
	(footprint ""
		(layer "F.Cu")
		(at 367.411 -100.076)
		(property "Reference" "Y7C2"
			(at -0.127 -1.49733 0)
			(unlocked yes)
			(layer "F.SilkS")
			(effects
				(font
					(size 0.7874 0.5842)
					(thickness 0.1524)
				)
			)
		)
		(property "Value" ""
			(at 0 0 0)
			(layer "F.Fab")
			(effects
				(font
					(size 1.27 1.27)
				)
			)
		)
		(duplicate_pad_numbers_are_jumpers no)
		(fp_line
			(start -0.8001 1.9558)
			(end -0.8001 1.0922)
			(stroke
				(width 0.1524)
				(type default)
			)
			(layer "F.SilkS")
		)
		(fp_line
			(start 0.8001 1.9558)
			(end 0.8001 1.0922)
			(stroke
				(width 0.1524)
				(type default)
			)
			(layer "F.SilkS")
		)
		(fp_rect
			(start -0.8001 3.173984)
			(end 0.8001 -0.125984)
			(stroke
				(width 0)
				(type default)
			)
			(fill no)
			(layer "F.CrtYd")
		)
		(fp_line
			(start -0.8001 -0.125984)
			(end -0.8001 3.173984)
			(stroke
				(width 0.1)
				(type default)
			)
			(layer "F.Fab")
		)
		(fp_line
			(start -0.8001 3.173984)
			(end 0.8001 3.173984)
			(stroke
				(width 0.1)
				(type default)
			)
			(layer "F.Fab")
		)
		(fp_line
			(start 0.8001 -0.125984)
			(end -0.8001 -0.125984)
			(stroke
				(width 0.1)
				(type default)
			)
			(layer "F.Fab")
		)
		(fp_line
			(start 0.8001 3.173984)
			(end 0.8001 -0.125984)
			(stroke
				(width 0.1)
				(type default)
			)
			(layer "F.Fab")
		)
		(pad "1" smd rect
			(at 0 0)
			(size 1.6002 1.524)
			(layers "F.Cu" "F.Mask" "F.Paste")
			(net "XTAL_33K_RTC1")
		)
		(pad "2" smd rect
			(at 0 3.048)
			(size 1.6002 1.524)
			(layers "F.Cu" "F.Mask" "F.Paste")
			(net "XTAL_33K_RTC2")
		)
	)
)
